(kicad_pcb
	(version 20260206)
	(generator "pcbnew")
	(generator_version "10.0")
	(general
		(thickness 1.6)
		(legacy_teardrops no)
	)
	(paper "A4")
	(title_block
		(title "Wiwynn_Tioga_Pass_MB.brd")
		(comment 1 "Tioga Pass / footprints 4565-4572 of 4770")
	)
	(layers
		(0 "F.Cu" signal "TOP")
		(4 "In1.Cu" signal "L2GND")
		(6 "In2.Cu" signal "L3")
		(8 "In3.Cu" signal "L4GND")
		(10 "In4.Cu" signal "L5")
		(12 "In5.Cu" signal "L6GND")
		(14 "In6.Cu" signal "L7VCC")
		(16 "In7.Cu" signal "L8VCC")
		(18 "In8.Cu" signal "L9GND")
		(20 "In9.Cu" signal "L10")
		(22 "In10.Cu" signal "L11GND")
		(24 "In11.Cu" signal "L12")
		(26 "In12.Cu" signal "L13GND")
		(2 "B.Cu" signal "BOTTOM")
		(9 "F.Adhes" user "F.Adhesive")
		(11 "B.Adhes" user "B.Adhesive")
		(13 "F.Paste" user "Package Geometry/Pastemask Top")
		(15 "B.Paste" user "Package Geometry/Pastemask Bottom")
		(5 "F.SilkS" user "Ref Des/Silkscreen Top")
		(7 "B.SilkS" user "Ref Des/Silkscreen Bottom")
		(1 "F.Mask" user "Board Geometry/Soldermask Top")
		(3 "B.Mask" user "Board Geometry/Soldermask Bottom")
		(17 "Dwgs.User" user "User.Drawings")
		(19 "Cmts.User" user "User.Comments")
		(21 "Eco1.User" user "User.Eco1")
		(23 "Eco2.User" user "User.Eco2")
		(25 "Edge.Cuts" user "Board Geometry/Outline")
		(27 "Margin" user)
		(31 "F.CrtYd" user "Package Geometry/Place Bound Top")
		(29 "B.CrtYd" user "Package Geometry/Place Bound Bottom")
		(35 "F.Fab" user "Ref Des/Assembly Top")
		(33 "B.Fab" user "Ref Des/Assembly Bottom")
	)
	(footprint ""
		(layer "B.Cu")
		(at 440.968638 -150.713186 180)
		(property "Reference" "R25W168"
			(at 0.8382 -0.67818 180)
			(unlocked yes)
			(layer "B.SilkS")
			(effects
				(font
					(size 0.4064 0.254)
					(thickness 0.1524)
				)
				(justify left mirror)
			)
		)
		(property "Value" ""
			(at 0 0 0)
			(layer "B.Fab")
			(effects
				(font
					(size 1.27 1.27)
				)
				(justify mirror)
			)
		)
		(duplicate_pad_numbers_are_jumpers no)
		(fp_poly
			(pts
				(xy 0.2794 -0.1016) (xy -0.2794 -0.1016) (xy -0.2794 0.9906) (xy 0.2794 0.9906)
			)
			(stroke
				(width 0)
				(type default)
			)
			(fill no)
			(layer "B.CrtYd")
		)
		(fp_line
			(start 0.2794 0.9906)
			(end -0.2794 0.9906)
			(stroke
				(width 0.1)
				(type default)
			)
			(layer "B.Fab")
		)
		(fp_line
			(start 0.2794 -0.1016)
			(end 0.2794 0.9906)
			(stroke
				(width 0.1)
				(type default)
			)
			(layer "B.Fab")
		)
		(fp_line
			(start -0.2794 0.9906)
			(end -0.2794 -0.1016)
			(stroke
				(width 0.1)
				(type default)
			)
			(layer "B.Fab")
		)
		(fp_line
			(start -0.2794 -0.1016)
			(end 0.2794 -0.1016)
			(stroke
				(width 0.1)
				(type default)
			)
			(layer "B.Fab")
		)
		(pad "1" smd rect
			(at 0 0)
			(size 0.508 0.508)
			(layers "B.Cu" "B.Mask" "B.Paste")
			(net "JTAG_BMC_TCK0")
		)
		(pad "2" smd rect
			(at 0 0.889)
			(size 0.508 0.508)
			(layers "B.Cu" "B.Mask" "B.Paste")
			(net "GND")
		)
		(zone
			(layer "B.Cu")
			(hatch none 0.5)
			(connect_pads
				(clearance 0)
			)
			(min_thickness 0.25)
			(keepout
				(tracks not_allowed)
				(vias allowed)
				(pads allowed)
				(copperpour not_allowed)
				(footprints allowed)
			)
			(placement
				(enabled no)
				(sheetname "")
			)
			(fill
				(thermal_gap 0.5)
				(thermal_bridge_width 0.5)
				(island_removal_mode 0)
			)
			(polygon
				(pts
					(xy 440.714638 -151.348186) (xy 441.222638 -151.348186) (xy 441.222638 -150.967186) (xy 440.714638 -150.967186)
				)
			)
		)
		(zone
			(layer "B.Cu")
			(hatch none 0.5)
			(connect_pads
				(clearance 0)
			)
			(min_thickness 0.25)
			(keepout
				(tracks allowed)
				(vias not_allowed)
				(pads allowed)
				(copperpour not_allowed)
				(footprints allowed)
			)
			(placement
				(enabled no)
				(sheetname "")
			)
			(fill
				(thermal_gap 0.5)
				(thermal_bridge_width 0.5)
				(island_removal_mode 0)
			)
			(polygon
				(pts
					(xy 440.714638 -150.967186) (xy 441.222638 -150.967186) (xy 441.222638 -151.348186) (xy 440.714638 -151.348186)
				)
			)
		)
	)
	(footprint ""
		(layer "B.Cu")
		(at 428.279052 -13.794994 -90)
		(property "Reference" "R9G31"
			(at 0 0 90)
			(layer "B.SilkS")
			(hide yes)
			(effects
				(font
					(size 1.27 1.27)
				)
				(justify mirror)
			)
		)
		(property "Value" ""
			(at 0 0 90)
			(layer "B.Fab")
			(effects
				(font
					(size 1.27 1.27)
				)
				(justify mirror)
			)
		)
		(duplicate_pad_numbers_are_jumpers no)
		(fp_poly
			(pts
				(xy 0.2794 -0.1016) (xy -0.2794 -0.1016) (xy -0.2794 0.9906) (xy 0.2794 0.9906)
			)
			(stroke
				(width 0)
				(type default)
			)
			(fill no)
			(layer "B.CrtYd")
		)
		(fp_line
			(start -0.2794 0.9906)
			(end -0.2794 -0.1016)
			(stroke
				(width 0.1)
				(type default)
			)
			(layer "B.Fab")
		)
		(fp_line
			(start 0.2794 0.9906)
			(end -0.2794 0.9906)
			(stroke
				(width 0.1)
				(type default)
			)
			(layer "B.Fab")
		)
		(fp_line
			(start -0.2794 -0.1016)
			(end 0.2794 -0.1016)
			(stroke
				(width 0.1)
				(type default)
			)
			(layer "B.Fab")
		)
		(fp_line
			(start 0.2794 -0.1016)
			(end 0.2794 0.9906)
			(stroke
				(width 0.1)
				(type default)
			)
			(layer "B.Fab")
		)
		(pad "1" smd rect
			(at 0 0 90)
			(size 0.508 0.508)
			(layers "B.Cu" "B.Mask" "B.Paste")
			(net "H_CPU0_MEMDEF_MEMHOT_LVT3_K_N")
		)
		(pad "2" smd rect
			(at 0 0.889 90)
			(size 0.508 0.508)
			(layers "B.Cu" "B.Mask" "B.Paste")
			(net "H_CPU0_MEMDEF_MEMHOT_LVT3_N")
		)
		(zone
			(layer "B.Cu")
			(hatch none 0.5)
			(connect_pads
				(clearance 0)
			)
			(min_thickness 0.25)
			(keepout
				(tracks not_allowed)
				(vias allowed)
				(pads allowed)
				(copperpour not_allowed)
				(footprints allowed)
			)
			(placement
				(enabled no)
				(sheetname "")
			)
			(fill
				(thermal_gap 0.5)
				(thermal_bridge_width 0.5)
				(island_removal_mode 0)
			)
			(polygon
				(pts
					(xy 427.644052 -13.540994) (xy 427.644052 -14.048994) (xy 428.025052 -14.048994) (xy 428.025052 -13.540994)
				)
			)
		)
		(zone
			(layer "B.Cu")
			(hatch none 0.5)
			(connect_pads
				(clearance 0)
			)
			(min_thickness 0.25)
			(keepout
				(tracks allowed)
				(vias not_allowed)
				(pads allowed)
				(copperpour not_allowed)
				(footprints allowed)
			)
			(placement
				(enabled no)
				(sheetname "")
			)
			(fill
				(thermal_gap 0.5)
				(thermal_bridge_width 0.5)
				(island_removal_mode 0)
			)
			(polygon
				(pts
					(xy 428.025052 -13.540994) (xy 428.025052 -14.048994) (xy 427.644052 -14.048994) (xy 427.644052 -13.540994)
				)
			)
		)
	)
	(footprint ""
		(layer "B.Cu")
		(at 49.4284 -93.7514)
		(property "Reference" "C9N22"
			(at 0 0 0)
			(layer "B.SilkS")
			(hide yes)
			(effects
				(font
					(size 1.27 1.27)
				)
				(justify mirror)
			)
		)
		(property "Value" ""
			(at 0 0 0)
			(layer "B.Fab")
			(effects
				(font
					(size 1.27 1.27)
				)
				(justify mirror)
			)
		)
		(duplicate_pad_numbers_are_jumpers no)
		(fp_poly
			(pts
				(xy 0.4953 -0.2032) (xy -0.4953 -0.2032) (xy -0.4953 1.6002) (xy 0.4953 1.6002)
			)
			(stroke
				(width 0)
				(type default)
			)
			(fill no)
			(layer "B.CrtYd")
		)
		(fp_line
			(start -0.4953 -0.2032)
			(end -0.4953 1.6002)
			(stroke
				(width 0.1)
				(type default)
			)
			(layer "B.Fab")
		)
		(fp_line
			(start -0.4953 1.6002)
			(end 0.4953 1.6002)
			(stroke
				(width 0.1)
				(type default)
			)
			(layer "B.Fab")
		)
		(fp_line
			(start 0.4953 -0.2032)
			(end -0.4953 -0.2032)
			(stroke
				(width 0.1)
				(type default)
			)
			(layer "B.Fab")
		)
		(fp_line
			(start 0.4953 1.6002)
			(end 0.4953 -0.2032)
			(stroke
				(width 0.1)
				(type default)
			)
			(layer "B.Fab")
		)
		(pad "1" smd rect
			(at 0 0 180)
			(size 0.762 0.889)
			(layers "B.Cu" "B.Mask" "B.Paste")
			(net "PVSA_CPU1")
		)
		(pad "2" smd rect
			(at 0 1.397 180)
			(size 0.762 0.889)
			(layers "B.Cu" "B.Mask" "B.Paste")
			(net "GND")
		)
		(zone
			(layer "B.Cu")
			(hatch none 0.5)
			(connect_pads
				(clearance 0)
			)
			(min_thickness 0.25)
			(keepout
				(tracks not_allowed)
				(vias allowed)
				(pads allowed)
				(copperpour not_allowed)
				(footprints allowed)
			)
			(placement
				(enabled no)
				(sheetname "")
			)
			(fill
				(thermal_gap 0.5)
				(thermal_bridge_width 0.5)
				(island_removal_mode 0)
			)
			(polygon
				(pts
					(xy 49.8094 -93.3069) (xy 49.0474 -93.3069) (xy 49.0474 -92.7989) (xy 49.8094 -92.7989)
				)
			)
		)
	)
	(footprint ""
		(layer "B.Cu")
		(at 395.351 -88.2015)
		(property "Reference" "R2N21"
			(at 0 0 0)
			(layer "B.SilkS")
			(hide yes)
			(effects
				(font
					(size 1.27 1.27)
				)
				(justify mirror)
			)
		)
		(property "Value" ""
			(at 0 0 0)
			(layer "B.Fab")
			(effects
				(font
					(size 1.27 1.27)
				)
				(justify mirror)
			)
		)
		(duplicate_pad_numbers_are_jumpers no)
		(fp_poly
			(pts
				(xy 0.2794 -0.1016) (xy -0.2794 -0.1016) (xy -0.2794 0.9906) (xy 0.2794 0.9906)
			)
			(stroke
				(width 0)
				(type default)
			)
			(fill no)
			(layer "B.CrtYd")
		)
		(fp_line
			(start -0.2794 -0.1016)
			(end 0.2794 -0.1016)
			(stroke
				(width 0.1)
				(type default)
			)
			(layer "B.Fab")
		)
		(fp_line
			(start -0.2794 0.9906)
			(end -0.2794 -0.1016)
			(stroke
				(width 0.1)
				(type default)
			)
			(layer "B.Fab")
		)
		(fp_line
			(start 0.2794 -0.1016)
			(end 0.2794 0.9906)
			(stroke
				(width 0.1)
				(type default)
			)
			(layer "B.Fab")
		)
		(fp_line
			(start 0.2794 0.9906)
			(end -0.2794 0.9906)
			(stroke
				(width 0.1)
				(type default)
			)
			(layer "B.Fab")
		)
		(pad "1" smd rect
			(at 0 0 180)
			(size 0.508 0.508)
			(layers "B.Cu" "B.Mask" "B.Paste")
			(net "SMB_LAN_STBY_LVC3_SCL_R2")
		)
		(pad "2" smd rect
			(at 0 0.889 180)
			(size 0.508 0.508)
			(layers "B.Cu" "B.Mask" "B.Paste")
			(net "SMB_LAN_STBY_LVC3_SCL")
		)
		(zone
			(layer "B.Cu")
			(hatch none 0.5)
			(connect_pads
				(clearance 0)
			)
			(min_thickness 0.25)
			(keepout
				(tracks allowed)
				(vias not_allowed)
				(pads allowed)
				(copperpour not_allowed)
				(footprints allowed)
			)
			(placement
				(enabled no)
				(sheetname "")
			)
			(fill
				(thermal_gap 0.5)
				(thermal_bridge_width 0.5)
				(island_removal_mode 0)
			)
			(polygon
				(pts
					(xy 395.605 -87.9475) (xy 395.097 -87.9475) (xy 395.097 -87.5665) (xy 395.605 -87.5665)
				)
			)
		)
		(zone
			(layer "B.Cu")
			(hatch none 0.5)
			(connect_pads
				(clearance 0)
			)
			(min_thickness 0.25)
			(keepout
				(tracks not_allowed)
				(vias allowed)
				(pads allowed)
				(copperpour not_allowed)
				(footprints allowed)
			)
			(placement
				(enabled no)
				(sheetname "")
			)
			(fill
				(thermal_gap 0.5)
				(thermal_bridge_width 0.5)
				(island_removal_mode 0)
			)
			(polygon
				(pts
					(xy 395.605 -87.5665) (xy 395.097 -87.5665) (xy 395.097 -87.9475) (xy 395.605 -87.9475)
				)
			)
		)
	)
	(footprint ""
		(layer "B.Cu")
		(at 109.880654 -85.06714)
		(property "Reference" "C7P1"
			(at 0 0 0)
			(layer "B.SilkS")
			(hide yes)
			(effects
				(font
					(size 1.27 1.27)
				)
				(justify mirror)
			)
		)
		(property "Value" ""
			(at 0 0 0)
			(layer "B.Fab")
			(effects
				(font
					(size 1.27 1.27)
				)
				(justify mirror)
			)
		)
		(duplicate_pad_numbers_are_jumpers no)
		(fp_poly
			(pts
				(xy 0.7239 -0.2159) (xy -0.7239 -0.2159) (xy -0.7239 1.9939) (xy 0.7239 1.9939)
			)
			(stroke
				(width 0)
				(type default)
			)
			(fill no)
			(layer "B.CrtYd")
		)
		(fp_line
			(start -0.7239 -0.2159)
			(end 0.7239 -0.2159)
			(stroke
				(width 0.1)
				(type default)
			)
			(layer "B.Fab")
		)
		(fp_line
			(start -0.7239 1.9939)
			(end -0.7239 -0.2159)
			(stroke
				(width 0.1)
				(type default)
			)
			(layer "B.Fab")
		)
		(fp_line
			(start 0.7239 -0.2159)
			(end 0.7239 1.9939)
			(stroke
				(width 0.1)
				(type default)
			)
			(layer "B.Fab")
		)
		(fp_line
			(start 0.7239 1.9939)
			(end -0.7239 1.9939)
			(stroke
				(width 0.1)
				(type default)
			)
			(layer "B.Fab")
		)
		(pad "1" smd rect
			(at 0 0 180)
			(size 1.27 1.016)
			(layers "B.Cu" "B.Mask" "B.Paste")
			(net "PVDDQ_KLM")
		)
		(pad "2" smd rect
			(at 0 1.778 180)
			(size 1.27 1.016)
			(layers "B.Cu" "B.Mask" "B.Paste")
			(net "GND")
		)
		(zone
			(layer "B.Cu")
			(hatch none 0.5)
			(connect_pads
				(clearance 0)
			)
			(min_thickness 0.25)
			(keepout
				(tracks not_allowed)
				(vias allowed)
				(pads allowed)
				(copperpour not_allowed)
				(footprints allowed)
			)
			(placement
				(enabled no)
				(sheetname "")
			)
			(fill
				(thermal_gap 0.5)
				(thermal_bridge_width 0.5)
				(island_removal_mode 0)
			)
			(polygon
				(pts
					(xy 110.515654 -84.55914) (xy 109.245654 -84.55914) (xy 109.245654 -83.79714) (xy 110.515654 -83.79714)
				)
			)
		)
	)
	(footprint ""
		(layer "B.Cu")
		(at 11.9126 -74.8284 180)
		(property "Reference" "R9P18"
			(at 0 0 0)
			(layer "B.SilkS")
			(hide yes)
			(effects
				(font
					(size 1.27 1.27)
				)
				(justify mirror)
			)
		)
		(property "Value" ""
			(at 0 0 0)
			(layer "B.Fab")
			(effects
				(font
					(size 1.27 1.27)
				)
				(justify mirror)
			)
		)
		(duplicate_pad_numbers_are_jumpers no)
		(fp_rect
			(start 0.2794 -0.1016)
			(end -0.2794 0.9906)
			(stroke
				(width 0)
				(type default)
			)
			(fill no)
			(layer "B.CrtYd")
		)
		(fp_line
			(start 0.2794 0.9906)
			(end -0.2794 0.9906)
			(stroke
				(width 0.1)
				(type default)
			)
			(layer "B.Fab")
		)
		(fp_line
			(start 0.2794 -0.1016)
			(end 0.2794 0.9906)
			(stroke
				(width 0.1)
				(type default)
			)
			(layer "B.Fab")
		)
		(fp_line
			(start -0.2794 0.9906)
			(end -0.2794 -0.1016)
			(stroke
				(width 0.1)
				(type default)
			)
			(layer "B.Fab")
		)
		(fp_line
			(start -0.2794 -0.1016)
			(end 0.2794 -0.1016)
			(stroke
				(width 0.1)
				(type default)
			)
			(layer "B.Fab")
		)
		(pad "1" smd rect
			(at 0 0)
			(size 0.508 0.508)
			(layers "B.Cu" "B.Mask" "B.Paste")
			(net "P12V_STBY")
		)
		(pad "2" smd rect
			(at 0 0.889)
			(size 0.508 0.508)
			(layers "B.Cu" "B.Mask" "B.Paste")
			(net "PWRGD_P12V_R")
		)
		(zone
			(layer "B.Cu")
			(hatch none 0.5)
			(connect_pads
				(clearance 0)
			)
			(min_thickness 0.25)
			(keepout
				(tracks allowed)
				(vias not_allowed)
				(pads allowed)
				(copperpour not_allowed)
				(footprints allowed)
			)
			(placement
				(enabled no)
				(sheetname "")
			)
			(fill
				(thermal_gap 0.5)
				(thermal_bridge_width 0.5)
				(island_removal_mode 0)
			)
			(polygon
				(pts
					(xy 11.6586 -75.0824) (xy 12.1666 -75.0824) (xy 12.1666 -75.4634) (xy 11.6586 -75.4634)
				)
			)
		)
		(zone
			(layer "B.Cu")
			(hatch none 0.5)
			(connect_pads
				(clearance 0)
			)
			(min_thickness 0.25)
			(keepout
				(tracks not_allowed)
				(vias allowed)
				(pads allowed)
				(copperpour not_allowed)
				(footprints allowed)
			)
			(placement
				(enabled no)
				(sheetname "")
			)
			(fill
				(thermal_gap 0.5)
				(thermal_bridge_width 0.5)
				(island_removal_mode 0)
			)
			(polygon
				(pts
					(xy 11.6586 -75.0824) (xy 12.1666 -75.0824) (xy 12.1666 -75.4634) (xy 11.6586 -75.4634)
				)
			)
		)
	)
	(footprint ""
		(layer "B.Cu")
		(at 1.27 -15.9512 90)
		(property "Reference" "CT32"
			(at 0.8382 -0.84963 90)
			(unlocked yes)
			(layer "B.SilkS")
			(effects
				(font
					(size 0.7874 0.5842)
					(thickness 0.1524)
				)
				(justify left mirror)
			)
		)
		(property "Value" ""
			(at 0 0 90)
			(layer "B.Fab")
			(effects
				(font
					(size 1.27 1.27)
				)
				(justify mirror)
			)
		)
		(duplicate_pad_numbers_are_jumpers no)
		(fp_poly
			(pts
				(xy -0.3048 -0.1016) (xy -0.3048 0.9906) (xy 0.3048 0.9906) (xy 0.3048 -0.1016)
			)
			(stroke
				(width 0)
				(type default)
			)
			(fill no)
			(layer "B.CrtYd")
		)
		(fp_line
			(start 0.3048 -0.1016)
			(end 0.3048 0.9906)
			(stroke
				(width 0.1)
				(type default)
			)
			(layer "B.Fab")
		)
		(fp_line
			(start -0.3048 -0.1016)
			(end 0.3048 -0.1016)
			(stroke
				(width 0.1)
				(type default)
			)
			(layer "B.Fab")
		)
		(fp_line
			(start 0.3048 0.9906)
			(end -0.3048 0.9906)
			(stroke
				(width 0.1)
				(type default)
			)
			(layer "B.Fab")
		)
		(fp_line
			(start -0.3048 0.9906)
			(end -0.3048 -0.1016)
			(stroke
				(width 0.1)
				(type default)
			)
			(layer "B.Fab")
		)
		(pad "1" smd rect
			(at 0 0 270)
			(size 0.508 0.508)
			(layers "B.Cu" "B.Mask" "B.Paste")
			(net "A_TSENSE_PVDDQ_GHJ")
		)
		(pad "2" smd rect
			(at 0 0.889 270)
			(size 0.508 0.508)
			(layers "B.Cu" "B.Mask" "B.Paste")
			(net "GND")
		)
		(zone
			(layer "B.Cu")
			(hatch none 0.5)
			(connect_pads
				(clearance 0)
			)
			(min_thickness 0.25)
			(keepout
				(tracks allowed)
				(vias not_allowed)
				(pads allowed)
				(copperpour not_allowed)
				(footprints allowed)
			)
			(placement
				(enabled no)
				(sheetname "")
			)
			(fill
				(thermal_gap 0.5)
				(thermal_bridge_width 0.5)
				(island_removal_mode 0)
			)
			(polygon
				(pts
					(xy 1.524 -16.2052) (xy 1.524 -15.6972) (xy 1.905 -15.6972) (xy 1.905 -16.2052)
				)
			)
		)
		(zone
			(layer "B.Cu")
			(hatch none 0.5)
			(connect_pads
				(clearance 0)
			)
			(min_thickness 0.25)
			(keepout
				(tracks not_allowed)
				(vias allowed)
				(pads allowed)
				(copperpour not_allowed)
				(footprints allowed)
			)
			(placement
				(enabled no)
				(sheetname "")
			)
			(fill
				(thermal_gap 0.5)
				(thermal_bridge_width 0.5)
				(island_removal_mode 0)
			)
			(polygon
				(pts
					(xy 1.905 -16.2052) (xy 1.905 -15.6972) (xy 1.524 -15.6972) (xy 1.524 -16.2052)
				)
			)
		)
	)
	(footprint ""
		(layer "B.Cu")
		(at 390.144 -16.383 -90)
		(property "Reference" "C32W2"
			(at 0.8382 -0.67818 270)
			(unlocked yes)
			(layer "B.SilkS")
			(effects
				(font
					(size 0.4064 0.254)
					(thickness 0.1524)
				)
				(justify left mirror)
			)
		)
		(property "Value" ""
			(at 0 0 90)
			(layer "B.Fab")
			(effects
				(font
					(size 1.27 1.27)
				)
				(justify mirror)
			)
		)
		(duplicate_pad_numbers_are_jumpers no)
		(fp_poly
			(pts
				(xy -0.3048 -0.1016) (xy -0.3048 0.9906) (xy 0.3048 0.9906) (xy 0.3048 -0.1016)
			)
			(stroke
				(width 0)
				(type default)
			)
			(fill no)
			(layer "B.CrtYd")
		)
		(fp_line
			(start -0.3048 0.9906)
			(end -0.3048 -0.1016)
			(stroke
				(width 0.1)
				(type default)
			)
			(layer "B.Fab")
		)
		(fp_line
			(start 0.3048 0.9906)
			(end -0.3048 0.9906)
			(stroke
				(width 0.1)
				(type default)
			)
			(layer "B.Fab")
		)
		(fp_line
			(start -0.3048 -0.1016)
			(end 0.3048 -0.1016)
			(stroke
				(width 0.1)
				(type default)
			)
			(layer "B.Fab")
		)
		(fp_line
			(start 0.3048 -0.1016)
			(end 0.3048 0.9906)
			(stroke
				(width 0.1)
				(type default)
			)
			(layer "B.Fab")
		)
		(pad "1" smd rect
			(at 0 0 90)
			(size 0.508 0.508)
			(layers "B.Cu" "B.Mask" "B.Paste")
			(net "P3V3_STBY")
		)
		(pad "2" smd rect
			(at 0 0.889 90)
			(size 0.508 0.508)
			(layers "B.Cu" "B.Mask" "B.Paste")
			(net "GND")
		)
		(zone
			(layer "B.Cu")
			(hatch none 0.5)
			(connect_pads
				(clearance 0)
			)
			(min_thickness 0.25)
			(keepout
				(tracks not_allowed)
				(vias allowed)
				(pads allowed)
				(copperpour not_allowed)
				(footprints allowed)
			)
			(placement
				(enabled no)
				(sheetname "")
			)
			(fill
				(thermal_gap 0.5)
				(thermal_bridge_width 0.5)
				(island_removal_mode 0)
			)
			(polygon
				(pts
					(xy 389.509 -16.129) (xy 389.509 -16.637) (xy 389.89 -16.637) (xy 389.89 -16.129)
				)
			)
		)
		(zone
			(layer "B.Cu")
			(hatch none 0.5)
			(connect_pads
				(clearance 0)
			)
			(min_thickness 0.25)
			(keepout
				(tracks allowed)
				(vias not_allowed)
				(pads allowed)
				(copperpour not_allowed)
				(footprints allowed)
			)
			(placement
				(enabled no)
				(sheetname "")
			)
			(fill
				(thermal_gap 0.5)
				(thermal_bridge_width 0.5)
				(island_removal_mode 0)
			)
			(polygon
				(pts
					(xy 389.89 -16.129) (xy 389.89 -16.637) (xy 389.509 -16.637) (xy 389.509 -16.129)
				)
			)
		)
	)
)
